(kicad_pcb
	(version 20260206)
	(generator "pcbnew")
	(generator_version "10.0")
	(general
		(thickness 1.6)
		(legacy_teardrops no)
	)
	(paper "A4")
	(title_block
		(title "dpb — 14545-sa.0730WZS0815.brd")
		(comment 1 "Honey Badger (Wiwynn) / footprints 876-879 of 1066")
	)
	(layers
		(0 "F.Cu" signal "TOP")
		(4 "In1.Cu" signal "L2GND")
		(6 "In2.Cu" signal "L3")
		(8 "In3.Cu" signal "L4VCC")
		(10 "In4.Cu" signal "L5VCC")
		(12 "In5.Cu" signal "L6")
		(14 "In6.Cu" signal "L7GND")
		(2 "B.Cu" signal "BOTTOM")
		(9 "F.Adhes" user "F.Adhesive")
		(11 "B.Adhes" user "B.Adhesive")
		(13 "F.Paste" user "Package Geometry/Pastemask Top")
		(15 "B.Paste" user "Package Geometry/Pastemask Bottom")
		(5 "F.SilkS" user "Ref Des/Silkscreen Top")
		(7 "B.SilkS" user "Ref Des/Silkscreen Bottom")
		(1 "F.Mask" user "Board Geometry/Soldermask Top")
		(3 "B.Mask" user "Board Geometry/Soldermask Bottom")
		(17 "Dwgs.User" user "User.Drawings")
		(19 "Cmts.User" user "User.Comments")
		(21 "Eco1.User" user "User.Eco1")
		(23 "Eco2.User" user "User.Eco2")
		(25 "Edge.Cuts" user "Board Geometry/Outline")
		(27 "Margin" user)
		(31 "F.CrtYd" user "Package Geometry/Place Bound Top")
		(29 "B.CrtYd" user "Package Geometry/Place Bound Bottom")
		(35 "F.Fab" user "Ref Des/Assembly Top")
		(33 "B.Fab" user "Ref Des/Assembly Bottom")
	)
	(footprint ""
		(layer "F.Cu")
		(at 227.499926 -273.670014 90)
		(property "Reference" "SKT3"
			(at 0 0 90)
			(layer "F.SilkS")
			(hide yes)
			(effects
				(font
					(size 1.27 1.27)
				)
			)
		)
		(property "Value" "SKT-SATA14P-15P-12-GP"
			(at -22.6187 8.1788 90)
			(unlocked yes)
			(layer "F.Fab")
			(hide yes)
			(effects
				(font
					(size 1.016 1.016)
					(thickness 0.1524)
				)
			)
		)
		(property "Device Type" "87945-1001"
			(at -22.6187 6.6548 90)
			(unlocked yes)
			(layer "F.Fab")
			(hide yes)
			(effects
				(font
					(size 1.016 1.016)
					(thickness 0.1524)
				)
			)
		)
		(duplicate_pad_numbers_are_jumpers no)
		(fp_line
			(start -15.3924 -5.8547)
			(end -16.3576 -5.8547)
			(stroke
				(width 0.3302)
				(type default)
			)
			(layer "F.SilkS")
		)
		(fp_line
			(start 20.4724 -5.7658)
			(end 20.4724 -2.3114)
			(stroke
				(width 0.1524)
				(type default)
			)
			(layer "F.SilkS")
		)
		(fp_line
			(start -20.4724 -5.7658)
			(end 20.4724 -5.7658)
			(stroke
				(width 0.1524)
				(type default)
			)
			(layer "F.SilkS")
		)
		(fp_line
			(start 23.7617 -2.3114)
			(end 23.7617 2.3114)
			(stroke
				(width 0.1524)
				(type default)
			)
			(layer "F.SilkS")
		)
		(fp_line
			(start 20.4724 -2.3114)
			(end 23.7617 -2.3114)
			(stroke
				(width 0.1524)
				(type default)
			)
			(layer "F.SilkS")
		)
		(fp_line
			(start -20.4724 -2.3114)
			(end -20.4724 -5.7658)
			(stroke
				(width 0.1524)
				(type default)
			)
			(layer "F.SilkS")
		)
		(fp_line
			(start -23.7617 -2.3114)
			(end -20.4724 -2.3114)
			(stroke
				(width 0.1524)
				(type default)
			)
			(layer "F.SilkS")
		)
		(fp_line
			(start 23.117556 -0.5461)
			(end 23.117556 0.5461)
			(stroke
				(width 0.3048)
				(type default)
			)
			(layer "F.SilkS")
		)
		(fp_line
			(start -20.882356 -0.5461)
			(end -20.882356 0.5461)
			(stroke
				(width 0.3048)
				(type default)
			)
			(layer "F.SilkS")
		)
		(fp_line
			(start 20.882356 0.5461)
			(end 20.882356 -0.5461)
			(stroke
				(width 0.3048)
				(type default)
			)
			(layer "F.SilkS")
		)
		(fp_line
			(start -23.117556 0.5461)
			(end -23.117556 -0.5461)
			(stroke
				(width 0.3048)
				(type default)
			)
			(layer "F.SilkS")
		)
		(fp_line
			(start 23.7617 2.3114)
			(end 20.4724 2.3114)
			(stroke
				(width 0.1524)
				(type default)
			)
			(layer "F.SilkS")
		)
		(fp_line
			(start 20.4724 2.3114)
			(end 20.4724 9.652)
			(stroke
				(width 0.1524)
				(type default)
			)
			(layer "F.SilkS")
		)
		(fp_line
			(start -20.4724 2.3114)
			(end -23.7617 2.3114)
			(stroke
				(width 0.1524)
				(type default)
			)
			(layer "F.SilkS")
		)
		(fp_line
			(start -23.7617 2.3114)
			(end -23.7617 -2.3114)
			(stroke
				(width 0.1524)
				(type default)
			)
			(layer "F.SilkS")
		)
		(fp_line
			(start 17.8435 7.9502)
			(end -17.8435 7.9502)
			(stroke
				(width 0.1524)
				(type default)
			)
			(layer "F.SilkS")
		)
		(fp_line
			(start -17.8435 7.9502)
			(end -17.8435 9.652)
			(stroke
				(width 0.1524)
				(type default)
			)
			(layer "F.SilkS")
		)
		(fp_line
			(start 20.4724 9.652)
			(end 17.8435 9.652)
			(stroke
				(width 0.1524)
				(type default)
			)
			(layer "F.SilkS")
		)
		(fp_line
			(start 17.8435 9.652)
			(end 17.8435 7.9502)
			(stroke
				(width 0.1524)
				(type default)
			)
			(layer "F.SilkS")
		)
		(fp_line
			(start -17.8435 9.652)
			(end -20.4724 9.652)
			(stroke
				(width 0.1524)
				(type default)
			)
			(layer "F.SilkS")
		)
		(fp_line
			(start -20.4724 9.652)
			(end -20.4724 2.3114)
			(stroke
				(width 0.1524)
				(type default)
			)
			(layer "F.SilkS")
		)
		(fp_arc
			(start 20.882356 -0.5461)
			(mid 21.999956 -1.6637)
			(end 23.117556 -0.5461)
			(stroke
				(width 0.3048)
				(type default)
			)
			(layer "F.SilkS")
		)
		(fp_arc
			(start -23.117556 -0.5461)
			(mid -21.999956 -1.6637)
			(end -20.882356 -0.5461)
			(stroke
				(width 0.3048)
				(type default)
			)
			(layer "F.SilkS")
		)
		(fp_arc
			(start 23.117556 0.5461)
			(mid 21.999956 1.6637)
			(end 20.882356 0.5461)
			(stroke
				(width 0.3048)
				(type default)
			)
			(layer "F.SilkS")
		)
		(fp_arc
			(start -20.882356 0.5461)
			(mid -21.999956 1.6637)
			(end -23.117556 0.5461)
			(stroke
				(width 0.3048)
				(type default)
			)
			(layer "F.SilkS")
		)
		(fp_poly
			(pts
				(xy -15.87119 -5.838698) (xy -15.23619 -6.473698) (xy -16.50619 -6.473698)
			)
			(stroke
				(width 0)
				(type default)
			)
			(fill yes)
			(layer "F.SilkS")
		)
		(fp_poly
			(pts
				(xy -20.2184 -5.5118) (xy 20.2184 -5.5118) (xy 20.2184 -2.0574) (xy 23.5077 -2.0574) (xy 23.5077 2.0574)
				(xy 20.2184 2.0574) (xy 20.2184 9.398) (xy 18.0975 9.398) (xy 18.0975 7.6962) (xy -18.0975 7.6962)
				(xy -18.0975 9.398) (xy -20.2184 9.398) (xy -20.2184 2.0574) (xy -23.5077 2.0574) (xy -23.5077 -2.0574)
				(xy -20.2184 -2.0574)
			)
			(stroke
				(width 0)
				(type default)
			)
			(fill no)
			(layer "F.CrtYd")
		)
		(fp_poly
			(pts
				(xy -20.2184 -5.5118) (xy -20.2184 -6.0198) (xy -20.7264 -6.0198) (xy -20.7264 -2.5654) (xy -24.0157 -2.5654)
				(xy -24.0157 2.5654) (xy -20.7264 2.5654) (xy -20.7264 9.906) (xy -17.5895 9.906) (xy -17.5895 8.2042)
				(xy 17.5895 8.2042) (xy 17.5895 9.906) (xy 20.7264 9.906) (xy 20.7264 2.5654) (xy 24.0157 2.5654)
				(xy 24.0157 -2.5654) (xy 20.7264 -2.5654) (xy 20.7264 -6.0198) (xy -20.21586 -6.0198) (xy -20.21586 -5.5118)
				(xy 20.2184 -5.5118) (xy 20.2184 -2.0574) (xy 23.5077 -2.0574) (xy 23.5077 2.0574) (xy 20.2184 2.0574)
				(xy 20.2184 9.398) (xy 18.0975 9.398) (xy 18.0975 7.6962) (xy -18.0975 7.6962) (xy -18.0975 9.398)
				(xy -20.2184 9.398) (xy -20.2184 2.0574) (xy -23.5077 2.0574) (xy -23.5077 -2.0574) (xy -20.2184 -2.0574)
			)
			(stroke
				(width 0)
				(type default)
			)
			(fill no)
			(layer "F.CrtYd")
		)
		(fp_poly
			(pts
				(xy -20.7264 -6.0198) (xy -20.7264 -2.5654) (xy -24.0157 -2.5654) (xy -24.0157 2.5654) (xy -20.7264 2.5654)
				(xy -20.7264 9.906) (xy -17.5895 9.906) (xy -17.5895 8.2042) (xy 17.5895 8.2042) (xy 17.5895 9.906)
				(xy 20.7264 9.906) (xy 20.7264 2.5654) (xy 24.0157 2.5654) (xy 24.0157 -2.5654) (xy 20.7264 -2.5654)
				(xy 20.7264 -6.0198)
			)
			(stroke
				(width 0)
				(type default)
			)
			(fill no)
			(layer "F.Fab")
		)
		(pad "" np_thru_hole circle
			(at -18.999962 -2.350008 90)
			(size 0.254 0.254)
			(drill 1.8542)
			(layers "*.Cu" "*.Mask")
			(clearance 1.1557)
			(thermal_gap 1.1557)
		)
		(pad "" np_thru_hole circle
			(at 18.999962 -2.350008 90)
			(size 0.254 0.254)
			(drill 1.8542)
			(layers "*.Cu" "*.Mask")
			(clearance 1.1557)
			(thermal_gap 1.1557)
		)
		(pad "H1" thru_hole oval
			(at -21.999956 0 90)
			(size 1.524 2.6162)
			(drill oval 0.8128 1.905)
			(layers "*.Cu" "*.Mask")
			(remove_unused_layers no)
			(net "GND")
			(clearance 0.1524)
			(thermal_gap 0.1524)
		)
		(pad "H2" thru_hole oval
			(at 21.999956 0 90)
			(size 1.524 2.6162)
			(drill oval 0.8128 1.905)
			(layers "*.Cu" "*.Mask")
			(remove_unused_layers no)
			(net "GND")
			(clearance 0.1524)
			(thermal_gap 0.1524)
		)
		(pad "P1" smd rect
			(at -1.89992 -4.249928 90)
			(size 0.6604 2.3876)
			(layers "F.Cu" "F.Mask" "F.Paste")
			(net "Net_35")
		)
		(pad "P2" smd rect
			(at -0.62992 -4.249928 90)
			(size 0.6604 2.3876)
			(layers "F.Cu" "F.Mask" "F.Paste")
			(net "Net_34")
		)
		(pad "P3" smd rect
			(at 0.64008 -4.249928 90)
			(size 0.6604 2.3876)
			(layers "F.Cu" "F.Mask" "F.Paste")
			(net "Net_33")
		)
		(pad "P4" smd rect
			(at 1.91008 -4.249928 90)
			(size 0.6604 2.3876)
			(layers "F.Cu" "F.Mask" "F.Paste")
			(net "GND")
		)
		(pad "P5" smd rect
			(at 3.18008 -4.249928 90)
			(size 0.6604 2.3876)
			(layers "F.Cu" "F.Mask" "F.Paste")
			(net "HDD_PRSNT_NET2")
		)
		(pad "P6" smd rect
			(at 4.45008 -4.249928 90)
			(size 0.6604 2.3876)
			(layers "F.Cu" "F.Mask" "F.Paste")
			(net "GND")
		)
		(pad "P7" smd rect
			(at 5.72008 -4.249928 90)
			(size 0.6604 2.3876)
			(layers "F.Cu" "F.Mask" "F.Paste")
			(net "5V_PRE_2")
		)
		(pad "P8" smd rect
			(at 6.99008 -4.249928 90)
			(size 0.6604 2.3876)
			(layers "F.Cu" "F.Mask" "F.Paste")
			(net "P5V_HDD2")
		)
		(pad "P9" smd rect
			(at 8.26008 -4.249928 90)
			(size 0.6604 2.3876)
			(layers "F.Cu" "F.Mask" "F.Paste")
			(net "P5V_HDD2")
		)
		(pad "P10" smd rect
			(at 9.53008 -4.249928 90)
			(size 0.6604 2.3876)
			(layers "F.Cu" "F.Mask" "F.Paste")
			(net "GND")
		)
		(pad "P11" smd rect
			(at 10.80008 -4.249928 90)
			(size 0.6604 2.3876)
			(layers "F.Cu" "F.Mask" "F.Paste")
			(net "ACT_HDD2")
		)
		(pad "P12" smd rect
			(at 12.07008 -4.249928 90)
			(size 0.6604 2.3876)
			(layers "F.Cu" "F.Mask" "F.Paste")
			(net "GND")
		)
		(pad "P13" smd rect
			(at 13.34008 -4.249928 90)
			(size 0.6604 2.3876)
			(layers "F.Cu" "F.Mask" "F.Paste")
			(net "12V_PRE_2")
		)
		(pad "P14" smd rect
			(at 14.61008 -4.249928 90)
			(size 0.6604 2.3876)
			(layers "F.Cu" "F.Mask" "F.Paste")
			(net "P12V_HDD2")
		)
		(pad "P15" smd rect
			(at 15.88008 -4.249928 90)
			(size 0.6604 2.3876)
			(layers "F.Cu" "F.Mask" "F.Paste")
			(net "P12V_HDD2")
		)
		(pad "S1" smd rect
			(at -15.86992 -4.249928 90)
			(size 0.6604 2.3876)
			(layers "F.Cu" "F.Mask" "F.Paste")
			(net "GND")
		)
		(pad "S2" smd rect
			(at -14.59992 -4.249928 90)
			(size 0.6604 2.3876)
			(layers "F.Cu" "F.Mask" "F.Paste")
			(net "SAS2X28_A_HDD2_TX_+")
		)
		(pad "S3" smd rect
			(at -13.32992 -4.249928 90)
			(size 0.6604 2.3876)
			(layers "F.Cu" "F.Mask" "F.Paste")
			(net "SAS2X28_A_HDD2_TX_-")
		)
		(pad "S4" smd rect
			(at -12.05992 -4.249928 90)
			(size 0.6604 2.3876)
			(layers "F.Cu" "F.Mask" "F.Paste")
			(net "GND")
		)
		(pad "S5" smd rect
			(at -10.78992 -4.249928 90)
			(size 0.6604 2.3876)
			(layers "F.Cu" "F.Mask" "F.Paste")
			(net "SAS2X28_DRIVE_RX_N_A2")
		)
		(pad "S6" smd rect
			(at -9.51992 -4.249928 90)
			(size 0.6604 2.3876)
			(layers "F.Cu" "F.Mask" "F.Paste")
			(net "SAS2X28_DRIVE_RX_P_A2")
		)
		(pad "S7" smd rect
			(at -8.24992 -4.249928 90)
			(size 0.6604 2.3876)
			(layers "F.Cu" "F.Mask" "F.Paste")
			(net "GND")
		)
		(pad "S8" smd rect
			(at -7.480046 -2.100072 90)
			(size 0.508 1.905)
			(layers "F.Cu" "F.Mask" "F.Paste")
			(net "GND")
		)
		(pad "S9" smd rect
			(at -6.679946 -2.100072 90)
			(size 0.508 1.905)
			(layers "F.Cu" "F.Mask" "F.Paste")
			(net "SAS2X28_B_HDD2_TX_+")
		)
		(pad "S10" smd rect
			(at -5.8801 -2.100072 90)
			(size 0.508 1.905)
			(layers "F.Cu" "F.Mask" "F.Paste")
			(net "SAS2X28_B_HDD2_TX_-")
		)
		(pad "S11" smd rect
			(at -5.08 -2.100072 90)
			(size 0.508 1.905)
			(layers "F.Cu" "F.Mask" "F.Paste")
			(net "GND")
		)
		(pad "S12" smd rect
			(at -4.2799 -2.100072 90)
			(size 0.508 1.905)
			(layers "F.Cu" "F.Mask" "F.Paste")
			(net "SAS2X28_DRIVE_RX_N_B2")
		)
		(pad "S13" smd rect
			(at -3.480054 -2.100072 90)
			(size 0.508 1.905)
			(layers "F.Cu" "F.Mask" "F.Paste")
			(net "SAS2X28_DRIVE_RX_P_B2")
		)
		(pad "S14" smd rect
			(at -2.679954 -2.100072 90)
			(size 0.508 1.905)
			(layers "F.Cu" "F.Mask" "F.Paste")
			(net "GND")
		)
		(zone
			(layers "F.Cu" "B.Cu" "In1.Cu" "In2.Cu" "In3.Cu" "In4.Cu" "In5.Cu" "In6.Cu")
			(hatch none 0.5)
			(connect_pads
				(clearance 0)
			)
			(min_thickness 0.25)
			(keepout
				(tracks not_allowed)
				(vias allowed)
				(pads allowed)
				(copperpour not_allowed)
				(footprints allowed)
			)
			(placement
				(enabled no)
				(sheetname "")
			)
			(fill
				(thermal_gap 0.5)
				(thermal_bridge_width 0.5)
				(island_removal_mode 0)
			)
			(polygon
				(pts
					(arc
						(start 226.381818 -292.669976)
						(mid 223.918018 -292.669976)
						(end 226.381818 -292.669976)
					)
				)
			)
		)
		(zone
			(layers "F.Cu" "B.Cu" "In1.Cu" "In2.Cu" "In3.Cu" "In4.Cu" "In5.Cu" "In6.Cu")
			(hatch none 0.5)
			(connect_pads
				(clearance 0)
			)
			(min_thickness 0.25)
			(keepout
				(tracks not_allowed)
				(vias allowed)
				(pads allowed)
				(copperpour not_allowed)
				(footprints allowed)
			)
			(placement
				(enabled no)
				(sheetname "")
			)
			(fill
				(thermal_gap 0.5)
				(thermal_bridge_width 0.5)
				(island_removal_mode 0)
			)
			(polygon
				(pts
					(arc
						(start 226.381818 -254.670052)
						(mid 223.918018 -254.670052)
						(end 226.381818 -254.670052)
					)
				)
			)
		)
	)
	(footprint ""
		(layer "F.Cu")
		(at 29.971746 -292.8112 180)
		(property "Reference" "R209"
			(at 0 0 180)
			(layer "F.SilkS")
			(hide yes)
			(effects
				(font
					(size 1.27 1.27)
				)
			)
		)
		(property "Value" "2R2010J-1-GP"
			(at 0.254 -8.0772 180)
			(unlocked yes)
			(layer "F.Fab")
			(hide yes)
			(effects
				(font
					(size 1.016 1.016)
					(thickness 0.1524)
				)
			)
		)
		(property "Device Type" "R2010H28"
			(at 0.254 -9.6774 180)
			(unlocked yes)
			(layer "F.Fab")
			(hide yes)
			(effects
				(font
					(size 1.016 1.016)
					(thickness 0.1524)
				)
			)
		)
		(duplicate_pad_numbers_are_jumpers no)
		(fp_line
			(start 1.651 3.302)
			(end 1.651 -3.302)
			(stroke
				(width 0.1524)
				(type default)
			)
			(layer "F.SilkS")
		)
		(fp_line
			(start 1.651 -3.302)
			(end -1.651 -3.302)
			(stroke
				(width 0.1524)
				(type default)
			)
			(layer "F.SilkS")
		)
		(fp_line
			(start -1.651 3.302)
			(end 1.651 3.302)
			(stroke
				(width 0.1524)
				(type default)
			)
			(layer "F.SilkS")
		)
		(fp_line
			(start -1.651 -3.302)
			(end -1.651 3.302)
			(stroke
				(width 0.1524)
				(type default)
			)
			(layer "F.SilkS")
		)
		(fp_rect
			(start -1.7272 -3.3782)
			(end 1.7272 3.3782)
			(stroke
				(width 0)
				(type default)
			)
			(fill no)
			(layer "F.CrtYd")
		)
		(fp_poly
			(pts
				(xy 1.7272 3.3782) (xy 1.7272 -3.3782) (xy -1.7272 -3.3782) (xy -1.7272 3.3782)
			)
			(stroke
				(width 0)
				(type default)
			)
			(fill no)
			(layer "F.Fab")
		)
		(pad "1" smd rect
			(at 0 -2.3495 180)
			(size 2.794 1.143)
			(layers "F.Cu" "F.Mask" "F.Paste")
			(net "12V_PRE_7")
		)
		(pad "2" smd rect
			(at 0 2.3495 180)
			(size 2.794 1.143)
			(layers "F.Cu" "F.Mask" "F.Paste")
			(net "P12V_HDD7")
		)
	)
	(footprint ""
		(layer "F.Cu")
		(at 26.02103 -139.061952 90)
		(property "Reference" "C311"
			(at 0 0 90)
			(layer "F.SilkS")
			(hide yes)
			(effects
				(font
					(size 1.27 1.27)
				)
			)
		)
		(property "Value" "SCD01U50V2KX-1GP"
			(at 1.1811 -2.7051 90)
			(unlocked yes)
			(layer "F.Fab")
			(hide yes)
			(effects
				(font
					(size 1.016 1.016)
					(thickness 0.1524)
				)
			)
		)
		(property "Device Type" "C402H22"
			(at 1.1811 -4.2291 90)
			(unlocked yes)
			(layer "F.Fab")
			(hide yes)
			(effects
				(font
					(size 1.016 1.016)
					(thickness 0.1524)
				)
			)
		)
		(duplicate_pad_numbers_are_jumpers no)
		(fp_rect
			(start -0.4318 0.9525)
			(end 0.4318 -0.9525)
			(stroke
				(width 0)
				(type default)
			)
			(fill no)
			(layer "F.CrtYd")
		)
		(fp_rect
			(start -0.4318 0.9525)
			(end 0.4318 -0.9525)
			(stroke
				(width 0)
				(type default)
			)
			(fill no)
			(layer "F.Fab")
		)
		(pad "1" smd custom
			(at 0 -0.4445 90)
			(size 0.1524 0.1524)
			(layers "F.Cu" "F.Mask" "F.Paste")
			(net "SAS2X28_DRIVE_RX_P_A13")
			(options
				(clearance outline)
				(anchor circle)
			)
			(primitives
				(gr_poly
					(pts
						(arc
							(start 0.3048 -0.2032)
							(mid 0.275042 -0.275042)
							(end 0.2032 -0.3048)
						)
						(arc
							(start -0.2032 -0.3048)
							(mid -0.275042 -0.275042)
							(end -0.3048 -0.2032)
						)
						(arc
							(start -0.3048 0.2032)
							(mid -0.275042 0.275042)
							(end -0.2032 0.3048)
						)
						(arc
							(start 0.2032 0.3048)
							(mid 0.275042 0.275042)
							(end 0.3048 0.2032)
						)
					)
					(width 0)
					(fill yes)
				)
			)
		)
		(pad "2" smd custom
			(at 0 0.4445 90)
			(size 0.1524 0.1524)
			(layers "F.Cu" "F.Mask" "F.Paste")
			(net "SAS2X28_A_HDD13_RX_+")
			(options
				(clearance outline)
				(anchor circle)
			)
			(primitives
				(gr_poly
					(pts
						(arc
							(start 0.3048 -0.2032)
							(mid 0.275042 -0.275042)
							(end 0.2032 -0.3048)
						)
						(arc
							(start -0.2032 -0.3048)
							(mid -0.275042 -0.275042)
							(end -0.3048 -0.2032)
						)
						(arc
							(start -0.3048 0.2032)
							(mid -0.275042 0.275042)
							(end -0.2032 0.3048)
						)
						(arc
							(start 0.2032 0.3048)
							(mid 0.275042 0.275042)
							(end 0.3048 0.2032)
						)
					)
					(width 0)
					(fill yes)
				)
			)
		)
	)
	(footprint ""
		(layer "F.Cu")
		(at 30.225746 -387.4897)
		(property "Reference" "TP31"
			(at 0 0 0)
			(layer "F.SilkS")
			(hide yes)
			(effects
				(font
					(size 1.27 1.27)
				)
			)
		)
		(property "Value" "TPAD32-GP"
			(at 0 -3.166364 0)
			(unlocked yes)
			(layer "F.Fab")
			(hide yes)
			(effects
				(font
					(size 1.016 1.016)
					(thickness 0.1524)
				)
			)
		)
		(property "Device Type" "TPAD32"
			(at 0 -4.690618 0)
			(unlocked yes)
			(layer "F.Fab")
			(hide yes)
			(effects
				(font
					(size 1.016 1.016)
					(thickness 0.1524)
				)
			)
		)
		(duplicate_pad_numbers_are_jumpers no)
		(fp_poly
			(pts
				(arc
					(start 0.4064 0)
					(mid -0.4064 0)
					(end 0.4064 0)
				)
			)
			(stroke
				(width 0)
				(type default)
			)
			(fill no)
			(layer "F.CrtYd")
		)
		(fp_poly
			(pts
				(arc
					(start 0.7112 0)
					(mid -0.7112 0)
					(end 0.7112 0)
				)
			)
			(stroke
				(width 0)
				(type default)
			)
			(fill no)
			(layer "F.Fab")
		)
		(pad "1" smd circle
			(at 0 0)
			(size 0.8128 0.8128)
			(layers "F.Cu" "F.Mask" "F.Paste")
			(net "ACT_HDD6")
		)
	)
)
